(kicad_pcb
	(version 20260206)
	(generator "pcbnew")
	(generator_version "10.0")
	(general
		(thickness 1.6)
		(legacy_teardrops no)
	)
	(paper "A4")
	(title_block
		(title "peb — Lightning_PEB_BRD.brd")
		(comment 1 "Lightning (Wiwynn / Facebook NVMe JBOF) / footprints 1759-1766 of 2563")
	)
	(layers
		(0 "F.Cu" signal "TOP")
		(4 "In1.Cu" signal "L2GND")
		(6 "In2.Cu" signal "L3")
		(8 "In3.Cu" signal "L4VCC")
		(10 "In4.Cu" signal "L5VCC")
		(12 "In5.Cu" signal "L6")
		(14 "In6.Cu" signal "L7GND")
		(2 "B.Cu" signal "BOTTOM")
		(9 "F.Adhes" user "F.Adhesive")
		(11 "B.Adhes" user "B.Adhesive")
		(13 "F.Paste" user "Package Geometry/Pastemask Top")
		(15 "B.Paste" user "Package Geometry/Pastemask Bottom")
		(5 "F.SilkS" user "Ref Des/Silkscreen Top")
		(7 "B.SilkS" user "Ref Des/Silkscreen Bottom")
		(1 "F.Mask" user "Board Geometry/Soldermask Top")
		(3 "B.Mask" user "Board Geometry/Soldermask Bottom")
		(17 "Dwgs.User" user "User.Drawings")
		(19 "Cmts.User" user "User.Comments")
		(21 "Eco1.User" user "User.Eco1")
		(23 "Eco2.User" user "User.Eco2")
		(25 "Edge.Cuts" user "Board Geometry/Outline")
		(27 "Margin" user)
		(31 "F.CrtYd" user "Package Geometry/Place Bound Top")
		(29 "B.CrtYd" user "Package Geometry/Place Bound Bottom")
		(35 "F.Fab" user "Ref Des/Assembly Top")
		(33 "B.Fab" user "Ref Des/Assembly Bottom")
	)
	(footprint ""
		(layer "B.Cu")
		(at 160.147 -88.4174 180)
		(property "Reference" "C715"
			(at 0 0 0)
			(layer "B.SilkS")
			(hide yes)
			(effects
				(font
					(size 1.27 1.27)
				)
				(justify mirror)
			)
		)
		(property "Value" "SCD1U10V2KX-5GP"
			(at -1.1811 -2.7051 180)
			(unlocked yes)
			(layer "B.Fab")
			(hide yes)
			(effects
				(font
					(size 1.016 1.016)
					(thickness 0.1524)
				)
				(justify mirror)
			)
		)
		(property "Device Type" "C402H22"
			(at -1.1811 -4.2291 180)
			(unlocked yes)
			(layer "B.Fab")
			(hide yes)
			(effects
				(font
					(size 1.016 1.016)
					(thickness 0.1524)
				)
				(justify mirror)
			)
		)
		(duplicate_pad_numbers_are_jumpers no)
		(fp_rect
			(start 0.4318 0.9525)
			(end -0.4318 -0.9525)
			(stroke
				(width 0)
				(type default)
			)
			(fill no)
			(layer "B.CrtYd")
		)
		(fp_rect
			(start 0.4318 0.9525)
			(end -0.4318 -0.9525)
			(stroke
				(width 0)
				(type default)
			)
			(fill no)
			(layer "B.Fab")
		)
		(pad "1" smd custom
			(at 0 -0.4445)
			(size 0.1524 0.1524)
			(layers "B.Cu" "B.Mask" "B.Paste")
			(net "P1V8_CLKGEN")
			(options
				(clearance outline)
				(anchor circle)
			)
			(primitives
				(gr_poly
					(pts
						(arc
							(start 0.3048 0.2032)
							(mid 0.275042 0.275042)
							(end 0.2032 0.3048)
						)
						(arc
							(start -0.2032 0.3048)
							(mid -0.275042 0.275042)
							(end -0.3048 0.2032)
						)
						(arc
							(start -0.3048 -0.2032)
							(mid -0.275042 -0.275042)
							(end -0.2032 -0.3048)
						)
						(arc
							(start 0.2032 -0.3048)
							(mid 0.275042 -0.275042)
							(end 0.3048 -0.2032)
						)
					)
					(width 0)
					(fill yes)
				)
			)
		)
		(pad "2" smd custom
			(at 0 0.4445)
			(size 0.1524 0.1524)
			(layers "B.Cu" "B.Mask" "B.Paste")
			(net "GND")
			(options
				(clearance outline)
				(anchor circle)
			)
			(primitives
				(gr_poly
					(pts
						(arc
							(start 0.3048 0.2032)
							(mid 0.275042 0.275042)
							(end 0.2032 0.3048)
						)
						(arc
							(start -0.2032 0.3048)
							(mid -0.275042 0.275042)
							(end -0.3048 0.2032)
						)
						(arc
							(start -0.3048 -0.2032)
							(mid -0.275042 -0.275042)
							(end -0.2032 -0.3048)
						)
						(arc
							(start 0.2032 -0.3048)
							(mid 0.275042 -0.275042)
							(end 0.3048 -0.2032)
						)
					)
					(width 0)
					(fill yes)
				)
			)
		)
	)
	(footprint ""
		(layer "B.Cu")
		(at 182.0164 -61.595)
		(property "Reference" "C585"
			(at 0 0 0)
			(layer "B.SilkS")
			(hide yes)
			(effects
				(font
					(size 1.27 1.27)
				)
				(justify mirror)
			)
		)
		(property "Value" "SC4D7U16V5KX-1-GP"
			(at 0.0762 -6.1214 0)
			(unlocked yes)
			(layer "B.Fab")
			(hide yes)
			(effects
				(font
					(size 1.016 1.016)
					(thickness 0.1524)
				)
				(justify mirror)
			)
		)
		(property "Device Type" "C805H56"
			(at 0.0762 -8.1534 0)
			(unlocked yes)
			(layer "B.Fab")
			(hide yes)
			(effects
				(font
					(size 1.016 1.016)
					(thickness 0.1524)
				)
				(justify mirror)
			)
		)
		(duplicate_pad_numbers_are_jumpers no)
		(fp_line
			(start -0.635 0)
			(end 0.635 0)
			(stroke
				(width 0.508)
				(type default)
			)
			(layer "B.SilkS")
		)
		(fp_rect
			(start 0.9652 1.778)
			(end -0.9652 -1.778)
			(stroke
				(width 0)
				(type default)
			)
			(fill no)
			(layer "B.CrtYd")
		)
		(fp_poly
			(pts
				(xy 0.9652 -1.778) (xy -0.9652 -1.778) (xy -0.9652 1.778) (xy 0.9652 1.778)
			)
			(stroke
				(width 0)
				(type default)
			)
			(fill no)
			(layer "B.Fab")
		)
		(pad "1" smd rect
			(at 0 -0.9652 180)
			(size 1.397 1.143)
			(layers "B.Cu" "B.Mask" "B.Paste")
			(net "DUT_AVD_PCIE")
		)
		(pad "2" smd rect
			(at 0 0.9652 180)
			(size 1.397 1.143)
			(layers "B.Cu" "B.Mask" "B.Paste")
			(net "GND")
		)
	)
	(footprint ""
		(layer "B.Cu")
		(at 222.999046 -203.69784 180)
		(property "Reference" "R4142"
			(at 0 0 0)
			(layer "B.SilkS")
			(hide yes)
			(effects
				(font
					(size 1.27 1.27)
				)
				(justify mirror)
			)
		)
		(property "Value" "4K7R2F-GP"
			(at -0.064008 -3.993896 180)
			(unlocked yes)
			(layer "B.Fab")
			(hide yes)
			(effects
				(font
					(size 1.016 1.016)
					(thickness 0.1524)
				)
				(justify mirror)
			)
		)
		(property "Device Type" "R402H16"
			(at -0.064008 -5.517896 180)
			(unlocked yes)
			(layer "B.Fab")
			(hide yes)
			(effects
				(font
					(size 1.016 1.016)
					(thickness 0.1524)
				)
				(justify mirror)
			)
		)
		(duplicate_pad_numbers_are_jumpers no)
		(fp_line
			(start 0.508 -0.9398)
			(end 0.508 0.9398)
			(stroke
				(width 0.1524)
				(type default)
			)
			(layer "B.SilkS")
		)
		(fp_line
			(start -0.508 -0.9398)
			(end 0.508 -0.9398)
			(stroke
				(width 0.1524)
				(type default)
			)
			(layer "B.SilkS")
		)
		(fp_rect
			(start 0.508 0.9398)
			(end -0.508 -0.9398)
			(stroke
				(width 0)
				(type default)
			)
			(fill no)
			(layer "B.CrtYd")
		)
		(fp_rect
			(start 0.508 0.9398)
			(end -0.508 -0.9398)
			(stroke
				(width 0)
				(type default)
			)
			(fill no)
			(layer "B.Fab")
		)
		(pad "1" smd custom
			(at 0 -0.4445)
			(size 0.1397 0.1397)
			(layers "B.Cu" "B.Mask" "B.Paste")
			(net "SSD_ATNLED#13")
			(options
				(clearance outline)
				(anchor circle)
			)
			(primitives
				(gr_poly
					(pts
						(arc
							(start -0.1778 0.2794)
							(mid -0.249642 0.249642)
							(end -0.2794 0.1778)
						)
						(arc
							(start -0.2794 -0.1778)
							(mid -0.249642 -0.249642)
							(end -0.1778 -0.2794)
						)
						(arc
							(start 0.1778 -0.2794)
							(mid 0.249642 -0.249642)
							(end 0.2794 -0.1778)
						)
						(arc
							(start 0.2794 0.1778)
							(mid 0.249642 0.249642)
							(end 0.1778 0.2794)
						)
					)
					(width 0)
					(fill yes)
				)
			)
		)
		(pad "2" smd custom
			(at 0 0.4445)
			(size 0.1397 0.1397)
			(layers "B.Cu" "B.Mask" "B.Paste")
			(net "P3V3_STBY")
			(options
				(clearance outline)
				(anchor circle)
			)
			(primitives
				(gr_poly
					(pts
						(arc
							(start -0.1778 0.2794)
							(mid -0.249642 0.249642)
							(end -0.2794 0.1778)
						)
						(arc
							(start -0.2794 -0.1778)
							(mid -0.249642 -0.249642)
							(end -0.1778 -0.2794)
						)
						(arc
							(start 0.1778 -0.2794)
							(mid 0.249642 -0.249642)
							(end 0.2794 -0.1778)
						)
						(arc
							(start 0.2794 0.1778)
							(mid 0.249642 0.249642)
							(end 0.1778 0.2794)
						)
					)
					(width 0)
					(fill yes)
				)
			)
		)
	)
	(footprint ""
		(layer "B.Cu")
		(at 42.926 -116.332)
		(property "Reference" "TP298"
			(at 0 0 0)
			(layer "B.SilkS")
			(hide yes)
			(effects
				(font
					(size 1.27 1.27)
				)
				(justify mirror)
			)
		)
		(property "Value" "TPAD28-2-GP"
			(at 0.0127 -1.6637 0)
			(unlocked yes)
			(layer "B.Fab")
			(hide yes)
			(effects
				(font
					(size 1.016 1.016)
					(thickness 0.1524)
				)
				(justify mirror)
			)
		)
		(property "Device Type" "TPAD28"
			(at 0.0127 -3.1877 0)
			(unlocked yes)
			(layer "B.Fab")
			(hide yes)
			(effects
				(font
					(size 1.016 1.016)
					(thickness 0.1524)
				)
				(justify mirror)
			)
		)
		(duplicate_pad_numbers_are_jumpers no)
		(fp_poly
			(pts
				(arc
					(start 0.3556 0)
					(mid -0.3556 0)
					(end 0.3556 0)
				)
			)
			(stroke
				(width 0)
				(type default)
			)
			(fill no)
			(layer "B.CrtYd")
		)
		(fp_poly
			(pts
				(arc
					(start 0.6096 0)
					(mid -0.6096 0)
					(end 0.6096 0)
				)
			)
			(stroke
				(width 0)
				(type default)
			)
			(fill no)
			(layer "B.Fab")
		)
		(pad "1" smd circle
			(at 0 0 180)
			(size 0.7112 0.7112)
			(layers "B.Cu" "B.Mask" "B.Paste")
			(net "TP_GPIOV7")
		)
	)
	(footprint ""
		(layer "B.Cu")
		(at 258.786884 -14.629638 -90)
		(property "Reference" "R693"
			(at 0 0 90)
			(layer "B.SilkS")
			(hide yes)
			(effects
				(font
					(size 1.27 1.27)
				)
				(justify mirror)
			)
		)
		(property "Value" "4K7R2F-GP"
			(at -0.064008 -3.993896 270)
			(unlocked yes)
			(layer "B.Fab")
			(hide yes)
			(effects
				(font
					(size 1.016 1.016)
					(thickness 0.1524)
				)
				(justify mirror)
			)
		)
		(property "Device Type" "R402H16"
			(at -0.064008 -5.517896 270)
			(unlocked yes)
			(layer "B.Fab")
			(hide yes)
			(effects
				(font
					(size 1.016 1.016)
					(thickness 0.1524)
				)
				(justify mirror)
			)
		)
		(duplicate_pad_numbers_are_jumpers no)
		(fp_line
			(start -0.508 -0.9398)
			(end 0.508 -0.9398)
			(stroke
				(width 0.1524)
				(type default)
			)
			(layer "B.SilkS")
		)
		(fp_line
			(start 0.508 -0.9398)
			(end 0.508 0.9398)
			(stroke
				(width 0.1524)
				(type default)
			)
			(layer "B.SilkS")
		)
		(fp_rect
			(start 0.508 0.9398)
			(end -0.508 -0.9398)
			(stroke
				(width 0)
				(type default)
			)
			(fill no)
			(layer "B.CrtYd")
		)
		(fp_rect
			(start 0.508 0.9398)
			(end -0.508 -0.9398)
			(stroke
				(width 0)
				(type default)
			)
			(fill no)
			(layer "B.Fab")
		)
		(pad "1" smd custom
			(at 0 -0.4445 90)
			(size 0.1397 0.1397)
			(layers "B.Cu" "B.Mask" "B.Paste")
			(net "Q40_D")
			(options
				(clearance outline)
				(anchor circle)
			)
			(primitives
				(gr_poly
					(pts
						(arc
							(start -0.1778 0.2794)
							(mid -0.249642 0.249642)
							(end -0.2794 0.1778)
						)
						(arc
							(start -0.2794 -0.1778)
							(mid -0.249642 -0.249642)
							(end -0.1778 -0.2794)
						)
						(arc
							(start 0.1778 -0.2794)
							(mid 0.249642 -0.249642)
							(end 0.2794 -0.1778)
						)
						(arc
							(start 0.2794 0.1778)
							(mid 0.249642 0.249642)
							(end 0.1778 0.2794)
						)
					)
					(width 0)
					(fill yes)
				)
			)
		)
		(pad "2" smd custom
			(at 0 0.4445 90)
			(size 0.1397 0.1397)
			(layers "B.Cu" "B.Mask" "B.Paste")
			(net "P3V3_STBY")
			(options
				(clearance outline)
				(anchor circle)
			)
			(primitives
				(gr_poly
					(pts
						(arc
							(start -0.1778 0.2794)
							(mid -0.249642 0.249642)
							(end -0.2794 0.1778)
						)
						(arc
							(start -0.2794 -0.1778)
							(mid -0.249642 -0.249642)
							(end -0.1778 -0.2794)
						)
						(arc
							(start 0.1778 -0.2794)
							(mid 0.249642 -0.249642)
							(end 0.2794 -0.1778)
						)
						(arc
							(start 0.2794 0.1778)
							(mid 0.249642 0.249642)
							(end 0.1778 0.2794)
						)
					)
					(width 0)
					(fill yes)
				)
			)
		)
	)
	(footprint ""
		(layer "B.Cu")
		(at 218.670124 -190.601092 180)
		(property "Reference" "R553"
			(at 0 0 0)
			(layer "B.SilkS")
			(hide yes)
			(effects
				(font
					(size 1.27 1.27)
				)
				(justify mirror)
			)
		)
		(property "Value" "10KR2F-2-GP"
			(at -0.064008 -3.993896 180)
			(unlocked yes)
			(layer "B.Fab")
			(hide yes)
			(effects
				(font
					(size 1.016 1.016)
					(thickness 0.1524)
				)
				(justify mirror)
			)
		)
		(property "Device Type" "R402H16"
			(at -0.064008 -5.517896 180)
			(unlocked yes)
			(layer "B.Fab")
			(hide yes)
			(effects
				(font
					(size 1.016 1.016)
					(thickness 0.1524)
				)
				(justify mirror)
			)
		)
		(duplicate_pad_numbers_are_jumpers no)
		(fp_line
			(start 0.508 -0.9398)
			(end 0.508 0.9398)
			(stroke
				(width 0.1524)
				(type default)
			)
			(layer "B.SilkS")
		)
		(fp_line
			(start -0.508 -0.9398)
			(end 0.508 -0.9398)
			(stroke
				(width 0.1524)
				(type default)
			)
			(layer "B.SilkS")
		)
		(fp_rect
			(start 0.508 0.9398)
			(end -0.508 -0.9398)
			(stroke
				(width 0)
				(type default)
			)
			(fill no)
			(layer "B.CrtYd")
		)
		(fp_rect
			(start 0.508 0.9398)
			(end -0.508 -0.9398)
			(stroke
				(width 0)
				(type default)
			)
			(fill no)
			(layer "B.Fab")
		)
		(pad "1" smd custom
			(at 0 -0.4445)
			(size 0.1397 0.1397)
			(layers "B.Cu" "B.Mask" "B.Paste")
			(net "P3V3_STBY")
			(options
				(clearance outline)
				(anchor circle)
			)
			(primitives
				(gr_poly
					(pts
						(arc
							(start -0.1778 0.2794)
							(mid -0.249642 0.249642)
							(end -0.2794 0.1778)
						)
						(arc
							(start -0.2794 -0.1778)
							(mid -0.249642 -0.249642)
							(end -0.1778 -0.2794)
						)
						(arc
							(start 0.1778 -0.2794)
							(mid 0.249642 -0.249642)
							(end 0.2794 -0.1778)
						)
						(arc
							(start 0.2794 0.1778)
							(mid 0.249642 0.249642)
							(end 0.1778 0.2794)
						)
					)
					(width 0)
					(fill yes)
				)
			)
		)
		(pad "2" smd custom
			(at 0 0.4445)
			(size 0.1397 0.1397)
			(layers "B.Cu" "B.Mask" "B.Paste")
			(net "IOEXP3_AD2")
			(options
				(clearance outline)
				(anchor circle)
			)
			(primitives
				(gr_poly
					(pts
						(arc
							(start -0.1778 0.2794)
							(mid -0.249642 0.249642)
							(end -0.2794 0.1778)
						)
						(arc
							(start -0.2794 -0.1778)
							(mid -0.249642 -0.249642)
							(end -0.1778 -0.2794)
						)
						(arc
							(start 0.1778 -0.2794)
							(mid 0.249642 -0.249642)
							(end 0.2794 -0.1778)
						)
						(arc
							(start 0.2794 0.1778)
							(mid 0.249642 0.249642)
							(end 0.1778 0.2794)
						)
					)
					(width 0)
					(fill yes)
				)
			)
		)
	)
	(footprint ""
		(layer "B.Cu")
		(at 225.425 -198.882)
		(property "Reference" "R272"
			(at 0 0 0)
			(layer "B.SilkS")
			(hide yes)
			(effects
				(font
					(size 1.27 1.27)
				)
				(justify mirror)
			)
		)
		(property "Value" "4K7R2F-GP"
			(at -0.064008 -3.993896 0)
			(unlocked yes)
			(layer "B.Fab")
			(hide yes)
			(effects
				(font
					(size 1.016 1.016)
					(thickness 0.1524)
				)
				(justify mirror)
			)
		)
		(property "Device Type" "R402H16"
			(at -0.064008 -5.517896 0)
			(unlocked yes)
			(layer "B.Fab")
			(hide yes)
			(effects
				(font
					(size 1.016 1.016)
					(thickness 0.1524)
				)
				(justify mirror)
			)
		)
		(duplicate_pad_numbers_are_jumpers no)
		(fp_line
			(start -0.508 -0.9398)
			(end 0.508 -0.9398)
			(stroke
				(width 0.1524)
				(type default)
			)
			(layer "B.SilkS")
		)
		(fp_line
			(start 0.508 -0.9398)
			(end 0.508 0.9398)
			(stroke
				(width 0.1524)
				(type default)
			)
			(layer "B.SilkS")
		)
		(fp_rect
			(start 0.508 0.9398)
			(end -0.508 -0.9398)
			(stroke
				(width 0)
				(type default)
			)
			(fill no)
			(layer "B.CrtYd")
		)
		(fp_rect
			(start 0.508 0.9398)
			(end -0.508 -0.9398)
			(stroke
				(width 0)
				(type default)
			)
			(fill no)
			(layer "B.Fab")
		)
		(pad "1" smd custom
			(at 0 -0.4445 180)
			(size 0.1397 0.1397)
			(layers "B.Cu" "B.Mask" "B.Paste")
			(net "BMC_SSD_RST#0_A12")
			(options
				(clearance outline)
				(anchor circle)
			)
			(primitives
				(gr_poly
					(pts
						(arc
							(start -0.1778 0.2794)
							(mid -0.249642 0.249642)
							(end -0.2794 0.1778)
						)
						(arc
							(start -0.2794 -0.1778)
							(mid -0.249642 -0.249642)
							(end -0.1778 -0.2794)
						)
						(arc
							(start 0.1778 -0.2794)
							(mid 0.249642 -0.249642)
							(end 0.2794 -0.1778)
						)
						(arc
							(start 0.2794 0.1778)
							(mid 0.249642 0.249642)
							(end 0.1778 0.2794)
						)
					)
					(width 0)
					(fill yes)
				)
			)
		)
		(pad "2" smd custom
			(at 0 0.4445 180)
			(size 0.1397 0.1397)
			(layers "B.Cu" "B.Mask" "B.Paste")
			(net "P3V3_STBY")
			(options
				(clearance outline)
				(anchor circle)
			)
			(primitives
				(gr_poly
					(pts
						(arc
							(start -0.1778 0.2794)
							(mid -0.249642 0.249642)
							(end -0.2794 0.1778)
						)
						(arc
							(start -0.2794 -0.1778)
							(mid -0.249642 -0.249642)
							(end -0.1778 -0.2794)
						)
						(arc
							(start 0.1778 -0.2794)
							(mid 0.249642 -0.249642)
							(end 0.2794 -0.1778)
						)
						(arc
							(start 0.2794 0.1778)
							(mid 0.249642 0.249642)
							(end 0.1778 0.2794)
						)
					)
					(width 0)
					(fill yes)
				)
			)
		)
	)
	(footprint ""
		(layer "B.Cu")
		(at 47.117 -116.713)
		(property "Reference" "R223"
			(at 0 0 0)
			(layer "B.SilkS")
			(hide yes)
			(effects
				(font
					(size 1.27 1.27)
				)
				(justify mirror)
			)
		)
		(property "Value" "4K7R2F-GP"
			(at -0.064008 -3.993896 0)
			(unlocked yes)
			(layer "B.Fab")
			(hide yes)
			(effects
				(font
					(size 1.016 1.016)
					(thickness 0.1524)
				)
				(justify mirror)
			)
		)
		(property "Device Type" "R402H16"
			(at -0.064008 -5.517896 0)
			(unlocked yes)
			(layer "B.Fab")
			(hide yes)
			(effects
				(font
					(size 1.016 1.016)
					(thickness 0.1524)
				)
				(justify mirror)
			)
		)
		(duplicate_pad_numbers_are_jumpers no)
		(fp_line
			(start -0.508 -0.9398)
			(end 0.508 -0.9398)
			(stroke
				(width 0.1524)
				(type default)
			)
			(layer "B.SilkS")
		)
		(fp_line
			(start 0.508 -0.9398)
			(end 0.508 0.9398)
			(stroke
				(width 0.1524)
				(type default)
			)
			(layer "B.SilkS")
		)
		(fp_rect
			(start 0.508 0.9398)
			(end -0.508 -0.9398)
			(stroke
				(width 0)
				(type default)
			)
			(fill no)
			(layer "B.CrtYd")
		)
		(fp_rect
			(start 0.508 0.9398)
			(end -0.508 -0.9398)
			(stroke
				(width 0)
				(type default)
			)
			(fill no)
			(layer "B.Fab")
		)
		(pad "1" smd custom
			(at 0 -0.4445 180)
			(size 0.1397 0.1397)
			(layers "B.Cu" "B.Mask" "B.Paste")
			(net "PEER_TRAY_R")
			(options
				(clearance outline)
				(anchor circle)
			)
			(primitives
				(gr_poly
					(pts
						(arc
							(start -0.1778 0.2794)
							(mid -0.249642 0.249642)
							(end -0.2794 0.1778)
						)
						(arc
							(start -0.2794 -0.1778)
							(mid -0.249642 -0.249642)
							(end -0.1778 -0.2794)
						)
						(arc
							(start 0.1778 -0.2794)
							(mid 0.249642 -0.249642)
							(end 0.2794 -0.1778)
						)
						(arc
							(start 0.2794 0.1778)
							(mid 0.249642 0.249642)
							(end 0.1778 0.2794)
						)
					)
					(width 0)
					(fill yes)
				)
			)
		)
		(pad "2" smd custom
			(at 0 0.4445 180)
			(size 0.1397 0.1397)
			(layers "B.Cu" "B.Mask" "B.Paste")
			(net "P3V3_STBY")
			(options
				(clearance outline)
				(anchor circle)
			)
			(primitives
				(gr_poly
					(pts
						(arc
							(start -0.1778 0.2794)
							(mid -0.249642 0.249642)
							(end -0.2794 0.1778)
						)
						(arc
							(start -0.2794 -0.1778)
							(mid -0.249642 -0.249642)
							(end -0.1778 -0.2794)
						)
						(arc
							(start 0.1778 -0.2794)
							(mid 0.249642 -0.249642)
							(end 0.2794 -0.1778)
						)
						(arc
							(start 0.2794 0.1778)
							(mid 0.249642 0.249642)
							(end 0.1778 0.2794)
						)
					)
					(width 0)
					(fill yes)
				)
			)
		)
	)
)
